(kicad_pcb
	(version 20260206)
	(generator "pcbnew")
	(generator_version "10.0")
	(general
		(thickness 1.6)
		(legacy_teardrops no)
	)
	(paper "A4")
	(title_block
		(title "04192023_DAF0TMB3IC0_F0TG_MB_C_brd_V02_OCP.brd")
		(comment 1 "Grand Teton / footprints 4742-4750 of 8354")
	)
	(layers
		(0 "F.Cu" signal "TOP")
		(4 "In1.Cu" signal "GND")
		(6 "In2.Cu" signal "IN1")
		(8 "In3.Cu" signal "GND1")
		(10 "In4.Cu" signal "IN2")
		(12 "In5.Cu" signal "GND2")
		(14 "In6.Cu" signal "IN3")
		(16 "In7.Cu" signal "GND3")
		(18 "In8.Cu" signal "VCC")
		(20 "In9.Cu" signal "VCC1")
		(22 "In10.Cu" signal "GND4")
		(24 "In11.Cu" signal "IN4")
		(26 "In12.Cu" signal "GND5")
		(28 "In13.Cu" signal "IN5")
		(30 "In14.Cu" signal "GND6")
		(32 "In15.Cu" signal "IN6")
		(34 "In16.Cu" signal "GND7")
		(2 "B.Cu" signal "BOTTOM")
		(9 "F.Adhes" user "F.Adhesive")
		(11 "B.Adhes" user "B.Adhesive")
		(13 "F.Paste" user "Package Geometry/Pastemask Top")
		(15 "B.Paste" user "Package Geometry/Pastemask Bottom")
		(5 "F.SilkS" user "Ref Des/Silkscreen Top")
		(7 "B.SilkS" user "Ref Des/Silkscreen Bottom")
		(1 "F.Mask" user "Board Geometry/Soldermask Top")
		(3 "B.Mask" user "Board Geometry/Soldermask Bottom")
		(17 "Dwgs.User" user "User.Drawings")
		(19 "Cmts.User" user "User.Comments")
		(21 "Eco1.User" user "User.Eco1")
		(23 "Eco2.User" user "User.Eco2")
		(25 "Edge.Cuts" user "Board Geometry/Outline")
		(27 "Margin" user)
		(31 "F.CrtYd" user "Package Geometry/Place Bound Top")
		(29 "B.CrtYd" user "Package Geometry/Place Bound Bottom")
		(35 "F.Fab" user "Ref Des/Assembly Top")
		(33 "B.Fab" user "Ref Des/Assembly Bottom")
	)
	(footprint ""
		(layer "F.Cu")
		(at 180.074062 -32.935672 -90)
		(property "Reference" "R3998"
			(at 0 0 270)
			(layer "F.SilkS")
			(hide yes)
			(effects
				(font
					(size 1.27 1.27)
				)
			)
		)
		(property "Value" ""
			(at 0 0 270)
			(layer "F.Fab")
			(effects
				(font
					(size 1.27 1.27)
				)
			)
		)
		(duplicate_pad_numbers_are_jumpers no)
		(fp_line
			(start -0.7874 0.4064)
			(end -0.7874 -0.4064)
			(stroke
				(width 0.1524)
				(type default)
			)
			(layer "F.SilkS")
		)
		(fp_line
			(start 0.7874 0.4064)
			(end -0.7874 0.4064)
			(stroke
				(width 0.1524)
				(type default)
			)
			(layer "F.SilkS")
		)
		(fp_line
			(start -0.7874 -0.4064)
			(end 0.7874 -0.4064)
			(stroke
				(width 0.1524)
				(type default)
			)
			(layer "F.SilkS")
		)
		(fp_line
			(start 0.7874 -0.4064)
			(end 0.7874 0.4064)
			(stroke
				(width 0.1524)
				(type default)
			)
			(layer "F.SilkS")
		)
		(fp_line
			(start -0.67945 0.3048)
			(end -0.67945 -0.305054)
			(stroke
				(width 0.1)
				(type default)
			)
			(layer "F.Fab")
		)
		(fp_line
			(start -0.12065 0.3048)
			(end -0.67945 0.3048)
			(stroke
				(width 0.1)
				(type default)
			)
			(layer "F.Fab")
		)
		(fp_line
			(start 0.120396 0.3048)
			(end 0.120396 0.2794)
			(stroke
				(width 0.1)
				(type default)
			)
			(layer "F.Fab")
		)
		(fp_line
			(start 0.67945 0.3048)
			(end 0.120396 0.3048)
			(stroke
				(width 0.1)
				(type default)
			)
			(layer "F.Fab")
		)
		(fp_line
			(start -0.12065 0.2794)
			(end -0.12065 0.3048)
			(stroke
				(width 0.1)
				(type default)
			)
			(layer "F.Fab")
		)
		(fp_line
			(start 0.120396 0.2794)
			(end -0.12065 0.2794)
			(stroke
				(width 0.1)
				(type default)
			)
			(layer "F.Fab")
		)
		(fp_line
			(start -0.12065 -0.2794)
			(end 0.12065 -0.2794)
			(stroke
				(width 0.1)
				(type default)
			)
			(layer "F.Fab")
		)
		(fp_line
			(start 0.12065 -0.2794)
			(end 0.12065 -0.3048)
			(stroke
				(width 0.1)
				(type default)
			)
			(layer "F.Fab")
		)
		(fp_line
			(start 0.12065 -0.3048)
			(end 0.67945 -0.3048)
			(stroke
				(width 0.1)
				(type default)
			)
			(layer "F.Fab")
		)
		(fp_line
			(start 0.67945 -0.3048)
			(end 0.67945 0.3048)
			(stroke
				(width 0.1)
				(type default)
			)
			(layer "F.Fab")
		)
		(fp_line
			(start -0.67945 -0.305054)
			(end -0.12065 -0.305054)
			(stroke
				(width 0.1)
				(type default)
			)
			(layer "F.Fab")
		)
		(fp_line
			(start -0.12065 -0.305054)
			(end -0.12065 -0.2794)
			(stroke
				(width 0.1)
				(type default)
			)
			(layer "F.Fab")
		)
		(pad "1" smd circle
			(at -0.40005 0 270)
			(size 0 0)
			(layers "F.Cu" "F.Mask" "F.Paste")
			(net "P12V_SCM_EN")
		)
		(pad "2" smd circle
			(at 0.40005 0 270)
			(size 0 0)
			(layers "F.Cu" "F.Mask" "F.Paste")
			(net "P12V_SCM_EN_R2")
		)
	)
	(footprint ""
		(layer "F.Cu")
		(at 96.0628 -417.2204 180)
		(property "Reference" "R1454"
			(at 0 0 180)
			(layer "F.SilkS")
			(hide yes)
			(effects
				(font
					(size 1.27 1.27)
				)
			)
		)
		(property "Value" ""
			(at 0 0 180)
			(layer "F.Fab")
			(effects
				(font
					(size 1.27 1.27)
				)
			)
		)
		(duplicate_pad_numbers_are_jumpers no)
		(fp_line
			(start 0.32512 0.175006)
			(end -0.32512 0.175006)
			(stroke
				(width 0.1)
				(type default)
			)
			(layer "F.Fab")
		)
		(fp_line
			(start 0.32512 -0.175006)
			(end 0.32512 0.175006)
			(stroke
				(width 0.1)
				(type default)
			)
			(layer "F.Fab")
		)
		(fp_line
			(start -0.32512 0.175006)
			(end -0.32512 -0.175006)
			(stroke
				(width 0.1)
				(type default)
			)
			(layer "F.Fab")
		)
		(fp_line
			(start -0.32512 -0.175006)
			(end 0.32512 -0.175006)
			(stroke
				(width 0.1)
				(type default)
			)
			(layer "F.Fab")
		)
		(pad "1" smd rect
			(at -0.2667 0 180)
			(size 0.3048 0.381)
			(layers "F.Cu" "F.Mask" "F.Paste")
			(net "P1V8_CPU1_RT_1D")
		)
		(pad "2" smd rect
			(at 0.2667 0)
			(size 0.3048 0.381)
			(layers "F.Cu" "F.Mask" "F.Paste")
			(net "JTAG_TDI_RT_CPU1_P1")
		)
	)
	(footprint ""
		(layer "F.Cu")
		(at 194.31 -137.632948 90)
		(property "Reference" "R252"
			(at 0 0 90)
			(layer "F.SilkS")
			(hide yes)
			(effects
				(font
					(size 1.27 1.27)
				)
			)
		)
		(property "Value" ""
			(at 0 0 90)
			(layer "F.Fab")
			(effects
				(font
					(size 1.27 1.27)
				)
			)
		)
		(duplicate_pad_numbers_are_jumpers no)
		(fp_line
			(start 0.7874 -0.4064)
			(end 0.7874 0.4064)
			(stroke
				(width 0.1524)
				(type default)
			)
			(layer "F.SilkS")
		)
		(fp_line
			(start -0.7874 -0.4064)
			(end 0.7874 -0.4064)
			(stroke
				(width 0.1524)
				(type default)
			)
			(layer "F.SilkS")
		)
		(fp_line
			(start 0.7874 0.4064)
			(end -0.7874 0.4064)
			(stroke
				(width 0.1524)
				(type default)
			)
			(layer "F.SilkS")
		)
		(fp_line
			(start -0.7874 0.4064)
			(end -0.7874 -0.4064)
			(stroke
				(width 0.1524)
				(type default)
			)
			(layer "F.SilkS")
		)
		(fp_line
			(start -0.12065 -0.305054)
			(end -0.12065 -0.2794)
			(stroke
				(width 0.1)
				(type default)
			)
			(layer "F.Fab")
		)
		(fp_line
			(start -0.67945 -0.305054)
			(end -0.12065 -0.305054)
			(stroke
				(width 0.1)
				(type default)
			)
			(layer "F.Fab")
		)
		(fp_line
			(start 0.67945 -0.3048)
			(end 0.67945 0.3048)
			(stroke
				(width 0.1)
				(type default)
			)
			(layer "F.Fab")
		)
		(fp_line
			(start 0.12065 -0.3048)
			(end 0.67945 -0.3048)
			(stroke
				(width 0.1)
				(type default)
			)
			(layer "F.Fab")
		)
		(fp_line
			(start 0.12065 -0.2794)
			(end 0.12065 -0.3048)
			(stroke
				(width 0.1)
				(type default)
			)
			(layer "F.Fab")
		)
		(fp_line
			(start -0.12065 -0.2794)
			(end 0.12065 -0.2794)
			(stroke
				(width 0.1)
				(type default)
			)
			(layer "F.Fab")
		)
		(fp_line
			(start 0.120396 0.2794)
			(end -0.12065 0.2794)
			(stroke
				(width 0.1)
				(type default)
			)
			(layer "F.Fab")
		)
		(fp_line
			(start -0.12065 0.2794)
			(end -0.12065 0.3048)
			(stroke
				(width 0.1)
				(type default)
			)
			(layer "F.Fab")
		)
		(fp_line
			(start 0.67945 0.3048)
			(end 0.120396 0.3048)
			(stroke
				(width 0.1)
				(type default)
			)
			(layer "F.Fab")
		)
		(fp_line
			(start 0.120396 0.3048)
			(end 0.120396 0.2794)
			(stroke
				(width 0.1)
				(type default)
			)
			(layer "F.Fab")
		)
		(fp_line
			(start -0.12065 0.3048)
			(end -0.67945 0.3048)
			(stroke
				(width 0.1)
				(type default)
			)
			(layer "F.Fab")
		)
		(fp_line
			(start -0.67945 0.3048)
			(end -0.67945 -0.305054)
			(stroke
				(width 0.1)
				(type default)
			)
			(layer "F.Fab")
		)
		(pad "1" smd circle
			(at -0.40005 0 90)
			(size 0 0)
			(layers "F.Cu" "F.Mask" "F.Paste")
			(net "FM_CPU1_PWR_GD_IN")
		)
		(pad "2" smd circle
			(at 0.40005 0 90)
			(size 0 0)
			(layers "F.Cu" "F.Mask" "F.Paste")
			(net "CPU1_PWR_GD_IN")
		)
	)
	(footprint ""
		(layer "F.Cu")
		(at 398.595088 -384.32486 180)
		(property "Reference" "C867"
			(at 0 0 180)
			(layer "F.SilkS")
			(hide yes)
			(effects
				(font
					(size 1.27 1.27)
				)
			)
		)
		(property "Value" ""
			(at 0 0 180)
			(layer "F.Fab")
			(effects
				(font
					(size 1.27 1.27)
				)
			)
		)
		(duplicate_pad_numbers_are_jumpers no)
		(fp_line
			(start 0.299974 0.150114)
			(end -0.299974 0.150114)
			(stroke
				(width 0.1)
				(type default)
			)
			(layer "F.Fab")
		)
		(fp_line
			(start 0.299974 -0.150114)
			(end 0.299974 0.150114)
			(stroke
				(width 0.1)
				(type default)
			)
			(layer "F.Fab")
		)
		(fp_line
			(start -0.299974 0.150114)
			(end -0.299974 -0.150114)
			(stroke
				(width 0.1)
				(type default)
			)
			(layer "F.Fab")
		)
		(fp_line
			(start -0.299974 -0.150114)
			(end 0.299974 -0.150114)
			(stroke
				(width 0.1)
				(type default)
			)
			(layer "F.Fab")
		)
		(pad "1" smd rect
			(at -0.2667 0 180)
			(size 0.3048 0.381)
			(layers "F.Cu" "F.Mask" "F.Paste")
			(net "P5E_CPU0_P2_TX_C_DP<1>")
		)
		(pad "2" smd rect
			(at 0.2667 0 180)
			(size 0.3048 0.381)
			(layers "F.Cu" "F.Mask" "F.Paste")
			(net "P5E_CPU0_P2_TX_DP<1>")
		)
	)
	(footprint ""
		(layer "F.Cu")
		(at 236.650022 -352.49993)
		(property "Reference" "H105"
			(at -5.01269 -6.23189 0)
			(unlocked yes)
			(layer "F.SilkS")
			(effects
				(font
					(size 0.7874 0.5842)
					(thickness 0.1524)
				)
				(justify left)
			)
		)
		(property "Value" ""
			(at 0 0 0)
			(layer "F.Fab")
			(effects
				(font
					(size 1.27 1.27)
				)
			)
		)
		(duplicate_pad_numbers_are_jumpers no)
		(pad "1" thru_hole circle
			(at 0 0)
			(size 10.0076 10.0076)
			(drill 5.6134)
			(layers "*.Cu" "*.Mask")
			(remove_unused_layers no)
			(net "GND")
			(clearance -1.9431)
		)
	)
	(footprint ""
		(layer "F.Cu")
		(at 237.720378 -315.95568 90)
		(property "Reference" "PC6514"
			(at 0 0 90)
			(layer "F.SilkS")
			(hide yes)
			(effects
				(font
					(size 1.27 1.27)
				)
			)
		)
		(property "Value" ""
			(at 0 0 90)
			(layer "F.Fab")
			(effects
				(font
					(size 1.27 1.27)
				)
			)
		)
		(duplicate_pad_numbers_are_jumpers no)
		(fp_line
			(start 0.7874 -0.4064)
			(end 0.7874 0.4064)
			(stroke
				(width 0.1524)
				(type default)
			)
			(layer "F.SilkS")
		)
		(fp_line
			(start -0.7874 -0.4064)
			(end 0.7874 -0.4064)
			(stroke
				(width 0.1524)
				(type default)
			)
			(layer "F.SilkS")
		)
		(fp_line
			(start 0.7874 0.4064)
			(end -0.7874 0.4064)
			(stroke
				(width 0.1524)
				(type default)
			)
			(layer "F.SilkS")
		)
		(fp_line
			(start -0.7874 0.4064)
			(end -0.7874 -0.4064)
			(stroke
				(width 0.1524)
				(type default)
			)
			(layer "F.SilkS")
		)
		(fp_line
			(start -0.12065 -0.305054)
			(end -0.12065 -0.2794)
			(stroke
				(width 0.1)
				(type default)
			)
			(layer "F.Fab")
		)
		(fp_line
			(start -0.67945 -0.305054)
			(end -0.12065 -0.305054)
			(stroke
				(width 0.1)
				(type default)
			)
			(layer "F.Fab")
		)
		(fp_line
			(start 0.67945 -0.3048)
			(end 0.67945 0.3048)
			(stroke
				(width 0.1)
				(type default)
			)
			(layer "F.Fab")
		)
		(fp_line
			(start 0.12065 -0.3048)
			(end 0.67945 -0.3048)
			(stroke
				(width 0.1)
				(type default)
			)
			(layer "F.Fab")
		)
		(fp_line
			(start 0.12065 -0.2794)
			(end 0.12065 -0.3048)
			(stroke
				(width 0.1)
				(type default)
			)
			(layer "F.Fab")
		)
		(fp_line
			(start -0.12065 -0.2794)
			(end 0.12065 -0.2794)
			(stroke
				(width 0.1)
				(type default)
			)
			(layer "F.Fab")
		)
		(fp_line
			(start 0.120396 0.2794)
			(end -0.12065 0.2794)
			(stroke
				(width 0.1)
				(type default)
			)
			(layer "F.Fab")
		)
		(fp_line
			(start -0.12065 0.2794)
			(end -0.12065 0.3048)
			(stroke
				(width 0.1)
				(type default)
			)
			(layer "F.Fab")
		)
		(fp_line
			(start 0.67945 0.3048)
			(end 0.120396 0.3048)
			(stroke
				(width 0.1)
				(type default)
			)
			(layer "F.Fab")
		)
		(fp_line
			(start 0.120396 0.3048)
			(end 0.120396 0.2794)
			(stroke
				(width 0.1)
				(type default)
			)
			(layer "F.Fab")
		)
		(fp_line
			(start -0.12065 0.3048)
			(end -0.67945 0.3048)
			(stroke
				(width 0.1)
				(type default)
			)
			(layer "F.Fab")
		)
		(fp_line
			(start -0.67945 0.3048)
			(end -0.67945 -0.305054)
			(stroke
				(width 0.1)
				(type default)
			)
			(layer "F.Fab")
		)
		(pad "1" smd circle
			(at -0.40005 0 90)
			(size 0 0)
			(layers "F.Cu" "F.Mask" "F.Paste")
			(net "P1V8_CPU0_RT_1D")
		)
		(pad "2" smd circle
			(at 0.40005 0 90)
			(size 0 0)
			(layers "F.Cu" "F.Mask" "F.Paste")
			(net "GND")
		)
	)
	(footprint ""
		(layer "F.Cu")
		(at 363.215936 -256.012188 90)
		(property "Reference" "C2161"
			(at 0 0 90)
			(layer "F.SilkS")
			(hide yes)
			(effects
				(font
					(size 1.27 1.27)
				)
			)
		)
		(property "Value" ""
			(at 0 0 90)
			(layer "F.Fab")
			(effects
				(font
					(size 1.27 1.27)
				)
			)
		)
		(duplicate_pad_numbers_are_jumpers no)
		(fp_line
			(start 0.7874 -0.4064)
			(end 0.7874 0.4064)
			(stroke
				(width 0.1524)
				(type default)
			)
			(layer "F.SilkS")
		)
		(fp_line
			(start -0.7874 -0.4064)
			(end 0.7874 -0.4064)
			(stroke
				(width 0.1524)
				(type default)
			)
			(layer "F.SilkS")
		)
		(fp_line
			(start 0.7874 0.4064)
			(end -0.7874 0.4064)
			(stroke
				(width 0.1524)
				(type default)
			)
			(layer "F.SilkS")
		)
		(fp_line
			(start -0.7874 0.4064)
			(end -0.7874 -0.4064)
			(stroke
				(width 0.1524)
				(type default)
			)
			(layer "F.SilkS")
		)
		(fp_line
			(start -0.12065 -0.305054)
			(end -0.12065 -0.2794)
			(stroke
				(width 0.1)
				(type default)
			)
			(layer "F.Fab")
		)
		(fp_line
			(start -0.67945 -0.305054)
			(end -0.12065 -0.305054)
			(stroke
				(width 0.1)
				(type default)
			)
			(layer "F.Fab")
		)
		(fp_line
			(start 0.67945 -0.3048)
			(end 0.67945 0.3048)
			(stroke
				(width 0.1)
				(type default)
			)
			(layer "F.Fab")
		)
		(fp_line
			(start 0.12065 -0.3048)
			(end 0.67945 -0.3048)
			(stroke
				(width 0.1)
				(type default)
			)
			(layer "F.Fab")
		)
		(fp_line
			(start 0.12065 -0.2794)
			(end 0.12065 -0.3048)
			(stroke
				(width 0.1)
				(type default)
			)
			(layer "F.Fab")
		)
		(fp_line
			(start -0.12065 -0.2794)
			(end 0.12065 -0.2794)
			(stroke
				(width 0.1)
				(type default)
			)
			(layer "F.Fab")
		)
		(fp_line
			(start 0.120396 0.2794)
			(end -0.12065 0.2794)
			(stroke
				(width 0.1)
				(type default)
			)
			(layer "F.Fab")
		)
		(fp_line
			(start -0.12065 0.2794)
			(end -0.12065 0.3048)
			(stroke
				(width 0.1)
				(type default)
			)
			(layer "F.Fab")
		)
		(fp_line
			(start 0.67945 0.3048)
			(end 0.120396 0.3048)
			(stroke
				(width 0.1)
				(type default)
			)
			(layer "F.Fab")
		)
		(fp_line
			(start 0.120396 0.3048)
			(end 0.120396 0.2794)
			(stroke
				(width 0.1)
				(type default)
			)
			(layer "F.Fab")
		)
		(fp_line
			(start -0.12065 0.3048)
			(end -0.67945 0.3048)
			(stroke
				(width 0.1)
				(type default)
			)
			(layer "F.Fab")
		)
		(fp_line
			(start -0.67945 0.3048)
			(end -0.67945 -0.305054)
			(stroke
				(width 0.1)
				(type default)
			)
			(layer "F.Fab")
		)
		(pad "1" smd circle
			(at -0.40005 0 90)
			(size 0 0)
			(layers "F.Cu" "F.Mask" "F.Paste")
			(net "PVDDCR_SOC_P0")
		)
		(pad "2" smd circle
			(at 0.40005 0 90)
			(size 0 0)
			(layers "F.Cu" "F.Mask" "F.Paste")
			(net "GND")
		)
	)
	(footprint ""
		(layer "F.Cu")
		(at 135.616696 -370.57203 -90)
		(property "Reference" "C53"
			(at 0 0 270)
			(layer "F.SilkS")
			(hide yes)
			(effects
				(font
					(size 1.27 1.27)
				)
			)
		)
		(property "Value" ""
			(at 0 0 270)
			(layer "F.Fab")
			(effects
				(font
					(size 1.27 1.27)
				)
			)
		)
		(duplicate_pad_numbers_are_jumpers no)
		(fp_line
			(start -0.299974 0.150114)
			(end -0.299974 -0.150114)
			(stroke
				(width 0.1)
				(type default)
			)
			(layer "F.Fab")
		)
		(fp_line
			(start 0.299974 0.150114)
			(end -0.299974 0.150114)
			(stroke
				(width 0.1)
				(type default)
			)
			(layer "F.Fab")
		)
		(fp_line
			(start -0.299974 -0.150114)
			(end 0.299974 -0.150114)
			(stroke
				(width 0.1)
				(type default)
			)
			(layer "F.Fab")
		)
		(fp_line
			(start 0.299974 -0.150114)
			(end 0.299974 0.150114)
			(stroke
				(width 0.1)
				(type default)
			)
			(layer "F.Fab")
		)
		(pad "1" smd rect
			(at -0.2667 0 270)
			(size 0.3048 0.381)
			(layers "F.Cu" "F.Mask" "F.Paste")
			(net "P5E_CPU1_P3_TX_C_DP<13>")
		)
		(pad "2" smd rect
			(at 0.2667 0 270)
			(size 0.3048 0.381)
			(layers "F.Cu" "F.Mask" "F.Paste")
			(net "P5E_CPU1_P3_TX_DP<13>")
		)
	)
	(footprint ""
		(layer "F.Cu")
		(at 190.4238 -42.554398)
		(property "Reference" "R4071"
			(at 0 0 0)
			(layer "F.SilkS")
			(hide yes)
			(effects
				(font
					(size 1.27 1.27)
				)
			)
		)
		(property "Value" ""
			(at 0 0 0)
			(layer "F.Fab")
			(effects
				(font
					(size 1.27 1.27)
				)
			)
		)
		(duplicate_pad_numbers_are_jumpers no)
		(fp_line
			(start -0.7874 -0.4064)
			(end 0.7874 -0.4064)
			(stroke
				(width 0.1524)
				(type default)
			)
			(layer "F.SilkS")
		)
		(fp_line
			(start -0.7874 0.4064)
			(end -0.7874 -0.4064)
			(stroke
				(width 0.1524)
				(type default)
			)
			(layer "F.SilkS")
		)
		(fp_line
			(start 0.7874 -0.4064)
			(end 0.7874 0.4064)
			(stroke
				(width 0.1524)
				(type default)
			)
			(layer "F.SilkS")
		)
		(fp_line
			(start 0.7874 0.4064)
			(end -0.7874 0.4064)
			(stroke
				(width 0.1524)
				(type default)
			)
			(layer "F.SilkS")
		)
		(fp_line
			(start -0.67945 -0.305054)
			(end -0.12065 -0.305054)
			(stroke
				(width 0.1)
				(type default)
			)
			(layer "F.Fab")
		)
		(fp_line
			(start -0.67945 0.3048)
			(end -0.67945 -0.305054)
			(stroke
				(width 0.1)
				(type default)
			)
			(layer "F.Fab")
		)
		(fp_line
			(start -0.12065 -0.305054)
			(end -0.12065 -0.2794)
			(stroke
				(width 0.1)
				(type default)
			)
			(layer "F.Fab")
		)
		(fp_line
			(start -0.12065 -0.2794)
			(end 0.12065 -0.2794)
			(stroke
				(width 0.1)
				(type default)
			)
			(layer "F.Fab")
		)
		(fp_line
			(start -0.12065 0.2794)
			(end -0.12065 0.3048)
			(stroke
				(width 0.1)
				(type default)
			)
			(layer "F.Fab")
		)
		(fp_line
			(start -0.12065 0.3048)
			(end -0.67945 0.3048)
			(stroke
				(width 0.1)
				(type default)
			)
			(layer "F.Fab")
		)
		(fp_line
			(start 0.120396 0.2794)
			(end -0.12065 0.2794)
			(stroke
				(width 0.1)
				(type default)
			)
			(layer "F.Fab")
		)
		(fp_line
			(start 0.120396 0.3048)
			(end 0.120396 0.2794)
			(stroke
				(width 0.1)
				(type default)
			)
			(layer "F.Fab")
		)
		(fp_line
			(start 0.12065 -0.3048)
			(end 0.67945 -0.3048)
			(stroke
				(width 0.1)
				(type default)
			)
			(layer "F.Fab")
		)
		(fp_line
			(start 0.12065 -0.2794)
			(end 0.12065 -0.3048)
			(stroke
				(width 0.1)
				(type default)
			)
			(layer "F.Fab")
		)
		(fp_line
			(start 0.67945 -0.3048)
			(end 0.67945 0.3048)
			(stroke
				(width 0.1)
				(type default)
			)
			(layer "F.Fab")
		)
		(fp_line
			(start 0.67945 0.3048)
			(end 0.120396 0.3048)
			(stroke
				(width 0.1)
				(type default)
			)
			(layer "F.Fab")
		)
		(pad "1" smd circle
			(at -0.40005 0)
			(size 0 0)
			(layers "F.Cu" "F.Mask" "F.Paste")
			(net "P12V_AUX")
		)
		(pad "2" smd circle
			(at 0.40005 0)
			(size 0 0)
			(layers "F.Cu" "F.Mask" "F.Paste")
			(net "P12V_SCM_EN_G")
		)
	)
)
